(kicad_pcb
	(version 20260206)
	(generator "pcbnew")
	(generator_version "10.0")
	(general
		(thickness 1.6)
		(legacy_teardrops no)
	)
	(paper "A4")
	(title_block
		(title "Bryce Canyon_R.DPB_16317-1_OCP.brd")
		(comment 1 "Bryce Canyon / footprints 490-497 of 2099")
	)
	(layers
		(0 "F.Cu" signal "TOP")
		(4 "In1.Cu" signal "L2GND")
		(6 "In2.Cu" signal "L3")
		(8 "In3.Cu" signal "L4VCC")
		(10 "In4.Cu" signal "L5VCC")
		(12 "In5.Cu" signal "L6")
		(14 "In6.Cu" signal "L7GND")
		(2 "B.Cu" signal "BOTTOM")
		(9 "F.Adhes" user "F.Adhesive")
		(11 "B.Adhes" user "B.Adhesive")
		(13 "F.Paste" user "Package Geometry/Pastemask Top")
		(15 "B.Paste" user "Package Geometry/Pastemask Bottom")
		(5 "F.SilkS" user "Ref Des/Silkscreen Top")
		(7 "B.SilkS" user "Ref Des/Silkscreen Bottom")
		(1 "F.Mask" user "Board Geometry/Soldermask Top")
		(3 "B.Mask" user "Board Geometry/Soldermask Bottom")
		(17 "Dwgs.User" user "User.Drawings")
		(19 "Cmts.User" user "User.Comments")
		(21 "Eco1.User" user "User.Eco1")
		(23 "Eco2.User" user "User.Eco2")
		(25 "Edge.Cuts" user "Board Geometry/Outline")
		(27 "Margin" user)
		(31 "F.CrtYd" user "Package Geometry/Place Bound Top")
		(29 "B.CrtYd" user "Package Geometry/Place Bound Bottom")
		(35 "F.Fab" user "Ref Des/Assembly Top")
		(33 "B.Fab" user "Ref Des/Assembly Bottom")
	)
	(footprint ""
		(layer "F.Cu")
		(at 80.900016 -65.39992)
		(property "Reference" "LED15"
			(at 0 0 0)
			(layer "F.SilkS")
			(hide yes)
			(effects
				(font
					(size 1.27 1.27)
				)
			)
		)
		(property "Value" "LED-BY-19-GP"
			(at -2.132076 1.414018 0)
			(unlocked yes)
			(layer "F.Fab")
			(hide yes)
			(effects
				(font
					(size 1.016 1.016)
					(thickness 0.1524)
				)
			)
		)
		(property "Device Type" "LED-1615-4PH26"
			(at -2.132076 -0.109982 0)
			(unlocked yes)
			(layer "F.Fab")
			(hide yes)
			(effects
				(font
					(size 1.016 1.016)
					(thickness 0.1524)
				)
			)
		)
		(duplicate_pad_numbers_are_jumpers no)
		(fp_line
			(start -1.2954 0.254)
			(end -1.2954 1.6002)
			(stroke
				(width 0.508)
				(type default)
			)
			(layer "F.SilkS")
		)
		(fp_line
			(start -1.2954 1.6002)
			(end 1.2954 1.6002)
			(stroke
				(width 0.508)
				(type default)
			)
			(layer "F.SilkS")
		)
		(fp_line
			(start -1.1176 -1.4224)
			(end 1.1176 -1.4224)
			(stroke
				(width 0.1524)
				(type default)
			)
			(layer "F.SilkS")
		)
		(fp_line
			(start -1.1176 1.4224)
			(end -1.1176 -1.4224)
			(stroke
				(width 0.1524)
				(type default)
			)
			(layer "F.SilkS")
		)
		(fp_line
			(start 1.1176 -1.4224)
			(end 1.1176 1.4224)
			(stroke
				(width 0.1524)
				(type default)
			)
			(layer "F.SilkS")
		)
		(fp_line
			(start 1.1176 1.4224)
			(end -1.1176 1.4224)
			(stroke
				(width 0.1524)
				(type default)
			)
			(layer "F.SilkS")
		)
		(fp_line
			(start 1.2954 1.6002)
			(end 1.2954 0.254)
			(stroke
				(width 0.508)
				(type default)
			)
			(layer "F.SilkS")
		)
		(fp_rect
			(start -0.7493 0.8001)
			(end 0.7493 -0.8001)
			(stroke
				(width 0)
				(type default)
			)
			(fill no)
			(layer "F.CrtYd")
		)
		(fp_poly
			(pts
				(xy -1.3716 1.6764) (xy -1.3716 -1.6764) (xy 1.3716 -1.6764) (xy 1.3716 0.0635) (xy 0.7493 0.0635)
				(xy 0.7493 -0.8001) (xy -0.7493 -0.8001) (xy -0.7493 0.8001) (xy 0.7493 0.8001) (xy 0.7493 0.0762)
				(xy 1.3716 0.0762) (xy 1.3716 1.6764)
			)
			(stroke
				(width 0)
				(type default)
			)
			(fill no)
			(layer "F.CrtYd")
		)
		(fp_rect
			(start -1.3716 1.6764)
			(end 1.3716 -1.6764)
			(stroke
				(width 0)
				(type default)
			)
			(fill no)
			(layer "F.Fab")
		)
		(pad "1" smd rect
			(at 0.50038 -0.73025)
			(size 0.7112 0.8636)
			(layers "F.Cu" "F.Mask" "F.Paste")
			(net "DRV_ACT_14")
		)
		(pad "2" smd rect
			(at -0.50038 -0.73025)
			(size 0.7112 0.8636)
			(layers "F.Cu" "F.Mask" "F.Paste")
			(net "FLT_HDD14")
		)
		(pad "3" smd rect
			(at 0.50038 0.73025)
			(size 0.7112 0.8636)
			(layers "F.Cu" "F.Mask" "F.Paste")
			(net "DRV_ACT_14_N")
		)
		(pad "4" smd rect
			(at -0.50038 0.73025)
			(size 0.7112 0.8636)
			(layers "F.Cu" "F.Mask" "F.Paste")
			(net "FLT_HDD14_N")
		)
	)
	(footprint ""
		(layer "F.Cu")
		(at 127.761746 -368.282728 180)
		(property "Reference" "R151"
			(at 0 0 180)
			(layer "F.SilkS")
			(hide yes)
			(effects
				(font
					(size 1.27 1.27)
				)
			)
		)
		(property "Value" "300KR2F-GP"
			(at 0.064008 -3.993896 180)
			(unlocked yes)
			(layer "F.Fab")
			(hide yes)
			(effects
				(font
					(size 1.016 1.016)
					(thickness 0.1524)
				)
			)
		)
		(property "Device Type" "R402H16"
			(at 0.064008 -5.517896 180)
			(unlocked yes)
			(layer "F.Fab")
			(hide yes)
			(effects
				(font
					(size 1.016 1.016)
					(thickness 0.1524)
				)
			)
		)
		(duplicate_pad_numbers_are_jumpers no)
		(fp_line
			(start 0.508 -0.9398)
			(end -0.508 -0.9398)
			(stroke
				(width 0.1524)
				(type default)
			)
			(layer "F.SilkS")
		)
		(fp_line
			(start -0.508 -0.9398)
			(end -0.508 0.9398)
			(stroke
				(width 0.1524)
				(type default)
			)
			(layer "F.SilkS")
		)
		(fp_rect
			(start -0.508 0.9398)
			(end 0.508 -0.9398)
			(stroke
				(width 0)
				(type default)
			)
			(fill no)
			(layer "F.CrtYd")
		)
		(fp_rect
			(start -0.508 0.9398)
			(end 0.508 -0.9398)
			(stroke
				(width 0)
				(type default)
			)
			(fill no)
			(layer "F.Fab")
		)
		(pad "1" smd custom
			(at 0 -0.4445 180)
			(size 0.1397 0.1397)
			(layers "F.Cu" "F.Mask" "F.Paste")
			(net "GATE_FAN1_R")
			(options
				(clearance outline)
				(anchor circle)
			)
			(primitives
				(gr_poly
					(pts
						(arc
							(start -0.1778 -0.2794)
							(mid -0.249642 -0.249642)
							(end -0.2794 -0.1778)
						)
						(arc
							(start -0.2794 0.1778)
							(mid -0.249642 0.249642)
							(end -0.1778 0.2794)
						)
						(arc
							(start 0.1778 0.2794)
							(mid 0.249642 0.249642)
							(end 0.2794 0.1778)
						)
						(arc
							(start 0.2794 -0.1778)
							(mid 0.249642 -0.249642)
							(end 0.1778 -0.2794)
						)
					)
					(width 0)
					(fill yes)
				)
			)
		)
		(pad "2" smd custom
			(at 0 0.4445 180)
			(size 0.1397 0.1397)
			(layers "F.Cu" "F.Mask" "F.Paste")
			(net "P12V_IN")
			(options
				(clearance outline)
				(anchor circle)
			)
			(primitives
				(gr_poly
					(pts
						(arc
							(start -0.1778 -0.2794)
							(mid -0.249642 -0.249642)
							(end -0.2794 -0.1778)
						)
						(arc
							(start -0.2794 0.1778)
							(mid -0.249642 0.249642)
							(end -0.1778 0.2794)
						)
						(arc
							(start 0.1778 0.2794)
							(mid 0.249642 0.249642)
							(end 0.2794 0.1778)
						)
						(arc
							(start 0.2794 -0.1778)
							(mid 0.249642 -0.249642)
							(end 0.1778 -0.2794)
						)
					)
					(width 0)
					(fill yes)
				)
			)
		)
	)
	(footprint ""
		(layer "F.Cu")
		(at 163.90493 -366.120426 90)
		(property "Reference" "R1011"
			(at 0 0 90)
			(layer "F.SilkS")
			(hide yes)
			(effects
				(font
					(size 1.27 1.27)
				)
			)
		)
		(property "Value" "49K9R2F-L-GP"
			(at 0.064008 -3.993896 90)
			(unlocked yes)
			(layer "F.Fab")
			(hide yes)
			(effects
				(font
					(size 1.016 1.016)
					(thickness 0.1524)
				)
			)
		)
		(property "Device Type" "R402H16"
			(at 0.064008 -5.517896 90)
			(unlocked yes)
			(layer "F.Fab")
			(hide yes)
			(effects
				(font
					(size 1.016 1.016)
					(thickness 0.1524)
				)
			)
		)
		(duplicate_pad_numbers_are_jumpers no)
		(fp_line
			(start 0.508 -0.9398)
			(end -0.508 -0.9398)
			(stroke
				(width 0.1524)
				(type default)
			)
			(layer "F.SilkS")
		)
		(fp_line
			(start -0.508 -0.9398)
			(end -0.508 0.9398)
			(stroke
				(width 0.1524)
				(type default)
			)
			(layer "F.SilkS")
		)
		(fp_rect
			(start -0.508 0.9398)
			(end 0.508 -0.9398)
			(stroke
				(width 0)
				(type default)
			)
			(fill no)
			(layer "F.CrtYd")
		)
		(fp_rect
			(start -0.508 0.9398)
			(end 0.508 -0.9398)
			(stroke
				(width 0)
				(type default)
			)
			(fill no)
			(layer "F.Fab")
		)
		(pad "1" smd custom
			(at 0 -0.4445 90)
			(size 0.1397 0.1397)
			(layers "F.Cu" "F.Mask" "F.Paste")
			(net "P12V_CLIP")
			(options
				(clearance outline)
				(anchor circle)
			)
			(primitives
				(gr_poly
					(pts
						(arc
							(start -0.1778 -0.2794)
							(mid -0.249642 -0.249642)
							(end -0.2794 -0.1778)
						)
						(arc
							(start -0.2794 0.1778)
							(mid -0.249642 0.249642)
							(end -0.1778 0.2794)
						)
						(arc
							(start 0.1778 0.2794)
							(mid 0.249642 0.249642)
							(end 0.2794 0.1778)
						)
						(arc
							(start 0.2794 -0.1778)
							(mid 0.249642 -0.249642)
							(end 0.1778 -0.2794)
						)
					)
					(width 0)
					(fill yes)
				)
			)
		)
		(pad "2" smd custom
			(at 0 0.4445 90)
			(size 0.1397 0.1397)
			(layers "F.Cu" "F.Mask" "F.Paste")
			(net "MB0_CM_UV_R")
			(options
				(clearance outline)
				(anchor circle)
			)
			(primitives
				(gr_poly
					(pts
						(arc
							(start -0.1778 -0.2794)
							(mid -0.249642 -0.249642)
							(end -0.2794 -0.1778)
						)
						(arc
							(start -0.2794 0.1778)
							(mid -0.249642 0.249642)
							(end -0.1778 0.2794)
						)
						(arc
							(start 0.1778 0.2794)
							(mid 0.249642 0.249642)
							(end 0.2794 0.1778)
						)
						(arc
							(start 0.2794 -0.1778)
							(mid 0.249642 -0.249642)
							(end 0.1778 -0.2794)
						)
					)
					(width 0)
					(fill yes)
				)
			)
		)
	)
	(footprint ""
		(layer "F.Cu")
		(at 255.397 -230.886 180)
		(property "Reference" "R494"
			(at 0 0 180)
			(layer "F.SilkS")
			(hide yes)
			(effects
				(font
					(size 1.27 1.27)
				)
			)
		)
		(property "Value" "0R2J-2-GP"
			(at 0.064008 -3.993896 180)
			(unlocked yes)
			(layer "F.Fab")
			(hide yes)
			(effects
				(font
					(size 1.016 1.016)
					(thickness 0.1524)
				)
			)
		)
		(property "Device Type" "R402H16"
			(at 0.064008 -5.517896 180)
			(unlocked yes)
			(layer "F.Fab")
			(hide yes)
			(effects
				(font
					(size 1.016 1.016)
					(thickness 0.1524)
				)
			)
		)
		(duplicate_pad_numbers_are_jumpers no)
		(fp_line
			(start 0.508 -0.9398)
			(end -0.508 -0.9398)
			(stroke
				(width 0.1524)
				(type default)
			)
			(layer "F.SilkS")
		)
		(fp_line
			(start -0.508 -0.9398)
			(end -0.508 0.9398)
			(stroke
				(width 0.1524)
				(type default)
			)
			(layer "F.SilkS")
		)
		(fp_rect
			(start -0.508 0.9398)
			(end 0.508 -0.9398)
			(stroke
				(width 0)
				(type default)
			)
			(fill no)
			(layer "F.CrtYd")
		)
		(fp_rect
			(start -0.508 0.9398)
			(end 0.508 -0.9398)
			(stroke
				(width 0)
				(type default)
			)
			(fill no)
			(layer "F.Fab")
		)
		(pad "1" smd custom
			(at 0 -0.4445 180)
			(size 0.1397 0.1397)
			(layers "F.Cu" "F.Mask" "F.Paste")
			(net "SCC_FULL_PWR_EN_5V")
			(options
				(clearance outline)
				(anchor circle)
			)
			(primitives
				(gr_poly
					(pts
						(arc
							(start -0.1778 -0.2794)
							(mid -0.249642 -0.249642)
							(end -0.2794 -0.1778)
						)
						(arc
							(start -0.2794 0.1778)
							(mid -0.249642 0.249642)
							(end -0.1778 0.2794)
						)
						(arc
							(start 0.1778 0.2794)
							(mid 0.249642 0.249642)
							(end 0.2794 0.1778)
						)
						(arc
							(start 0.2794 -0.1778)
							(mid 0.249642 -0.249642)
							(end 0.1778 -0.2794)
						)
					)
					(width 0)
					(fill yes)
				)
			)
		)
		(pad "2" smd custom
			(at 0 0.4445 180)
			(size 0.1397 0.1397)
			(layers "F.Cu" "F.Mask" "F.Paste")
			(net "SCC_FULL_PWR_EN_5V_R")
			(options
				(clearance outline)
				(anchor circle)
			)
			(primitives
				(gr_poly
					(pts
						(arc
							(start -0.1778 -0.2794)
							(mid -0.249642 -0.249642)
							(end -0.2794 -0.1778)
						)
						(arc
							(start -0.2794 0.1778)
							(mid -0.249642 0.249642)
							(end -0.1778 0.2794)
						)
						(arc
							(start 0.1778 0.2794)
							(mid 0.249642 0.249642)
							(end 0.2794 0.1778)
						)
						(arc
							(start 0.2794 -0.1778)
							(mid 0.249642 -0.249642)
							(end 0.1778 -0.2794)
						)
					)
					(width 0)
					(fill yes)
				)
			)
		)
	)
	(footprint ""
		(layer "F.Cu")
		(at 475.107 -262.001 -90)
		(property "Reference" "C174"
			(at 0 0 270)
			(layer "F.SilkS")
			(hide yes)
			(effects
				(font
					(size 1.27 1.27)
				)
			)
		)
		(property "Value" "SC10U16V6KX-2GP"
			(at -0.0762 -5.1308 270)
			(unlocked yes)
			(layer "F.Fab")
			(hide yes)
			(effects
				(font
					(size 1.016 1.016)
					(thickness 0.1524)
				)
			)
		)
		(property "Device Type" "C1206H71"
			(at -0.127 -6.6548 270)
			(unlocked yes)
			(layer "F.Fab")
			(hide yes)
			(effects
				(font
					(size 1.016 1.016)
					(thickness 0.1524)
				)
			)
		)
		(duplicate_pad_numbers_are_jumpers no)
		(fp_line
			(start -1.016 2.2352)
			(end -1.016 0.8382)
			(stroke
				(width 0.1524)
				(type default)
			)
			(layer "F.SilkS")
		)
		(fp_line
			(start 1.016 2.2352)
			(end -1.016 2.2352)
			(stroke
				(width 0.1524)
				(type default)
			)
			(layer "F.SilkS")
		)
		(fp_line
			(start 1.016 0.8382)
			(end 1.016 2.2352)
			(stroke
				(width 0.1524)
				(type default)
			)
			(layer "F.SilkS")
		)
		(fp_line
			(start -1.016 -0.8382)
			(end -1.016 -2.2352)
			(stroke
				(width 0.1524)
				(type default)
			)
			(layer "F.SilkS")
		)
		(fp_line
			(start -1.016 -2.2352)
			(end 1.016 -2.2352)
			(stroke
				(width 0.1524)
				(type default)
			)
			(layer "F.SilkS")
		)
		(fp_line
			(start 1.016 -2.2352)
			(end 1.016 -0.8382)
			(stroke
				(width 0.1524)
				(type default)
			)
			(layer "F.SilkS")
		)
		(fp_rect
			(start -1.0922 2.3114)
			(end 1.0922 -2.3114)
			(stroke
				(width 0)
				(type default)
			)
			(fill no)
			(layer "F.CrtYd")
		)
		(fp_poly
			(pts
				(xy 1.0922 -2.3114) (xy 1.0922 2.3114) (xy -1.0922 2.3114) (xy -1.0922 -2.3114)
			)
			(stroke
				(width 0)
				(type default)
			)
			(fill no)
			(layer "F.Fab")
		)
		(pad "1" smd rect
			(at 0 -1.397 270)
			(size 1.651 1.27)
			(layers "F.Cu" "F.Mask" "F.Paste")
			(net "P5V_HDD11")
		)
		(pad "2" smd rect
			(at 0 1.397 270)
			(size 1.651 1.27)
			(layers "F.Cu" "F.Mask" "F.Paste")
			(net "GND")
		)
	)
	(footprint ""
		(layer "F.Cu")
		(at 428.117 -160.02 180)
		(property "Reference" "C308"
			(at 0 0 180)
			(layer "F.SilkS")
			(hide yes)
			(effects
				(font
					(size 1.27 1.27)
				)
			)
		)
		(property "Value" "SC4D7U25V5KX-1-GP"
			(at -0.0762 -6.1214 180)
			(unlocked yes)
			(layer "F.Fab")
			(hide yes)
			(effects
				(font
					(size 1.016 1.016)
					(thickness 0.1524)
				)
			)
		)
		(property "Device Type" "C805H58"
			(at -0.0762 -8.1534 180)
			(unlocked yes)
			(layer "F.Fab")
			(hide yes)
			(effects
				(font
					(size 1.016 1.016)
					(thickness 0.1524)
				)
			)
		)
		(duplicate_pad_numbers_are_jumpers no)
		(fp_line
			(start 0.635 0)
			(end -0.635 0)
			(stroke
				(width 0.508)
				(type default)
			)
			(layer "F.SilkS")
		)
		(fp_rect
			(start -0.9652 1.778)
			(end 0.9652 -1.778)
			(stroke
				(width 0)
				(type default)
			)
			(fill no)
			(layer "F.CrtYd")
		)
		(fp_poly
			(pts
				(xy -0.9652 -1.778) (xy 0.9652 -1.778) (xy 0.9652 1.778) (xy -0.9652 1.778)
			)
			(stroke
				(width 0)
				(type default)
			)
			(fill no)
			(layer "F.Fab")
		)
		(pad "1" smd rect
			(at 0 -0.9652 180)
			(size 1.397 1.143)
			(layers "F.Cu" "F.Mask" "F.Paste")
			(net "P12V_HDD21")
		)
		(pad "2" smd rect
			(at 0 0.9652 180)
			(size 1.397 1.143)
			(layers "F.Cu" "F.Mask" "F.Paste")
			(net "GND")
		)
	)
	(footprint ""
		(layer "F.Cu")
		(at 416.284664 -15.219426 -90)
		(property "Reference" "C457"
			(at 0 0 270)
			(layer "F.SilkS")
			(hide yes)
			(effects
				(font
					(size 1.27 1.27)
				)
			)
		)
		(property "Value" "SCD01U16V1KX-GP"
			(at -2.8321 -1.7399 270)
			(unlocked yes)
			(layer "F.Fab")
			(hide yes)
			(effects
				(font
					(size 1.016 1.016)
					(thickness 0.1524)
				)
			)
		)
		(property "Device Type" "C0201H13"
			(at -2.8321 -3.2639 270)
			(unlocked yes)
			(layer "F.Fab")
			(hide yes)
			(effects
				(font
					(size 1.016 1.016)
					(thickness 0.1524)
				)
			)
		)
		(duplicate_pad_numbers_are_jumpers no)
		(fp_rect
			(start -0.2794 0.6477)
			(end 0.2794 -0.6477)
			(stroke
				(width 0)
				(type default)
			)
			(fill no)
			(layer "F.CrtYd")
		)
		(fp_rect
			(start -0.2794 0.6477)
			(end 0.2794 -0.6477)
			(stroke
				(width 0)
				(type default)
			)
			(fill no)
			(layer "F.Fab")
		)
		(pad "1" smd custom
			(at 0 -0.2794 270)
			(size 0.0762 0.0762)
			(layers "F.Cu" "F.Mask" "F.Paste")
			(net "SAS_HDD_RX_N33")
			(options
				(clearance outline)
				(anchor circle)
			)
			(primitives
				(gr_poly
					(pts
						(arc
							(start 0.1524 -0.127)
							(mid 0.137521 -0.162921)
							(end 0.1016 -0.1778)
						)
						(arc
							(start -0.1016 -0.1778)
							(mid -0.137521 -0.162921)
							(end -0.1524 -0.127)
						)
						(arc
							(start -0.1524 0.127)
							(mid -0.137521 0.162921)
							(end -0.1016 0.1778)
						)
						(arc
							(start 0.1016 0.1778)
							(mid 0.137521 0.162921)
							(end 0.1524 0.127)
						)
					)
					(width 0)
					(fill yes)
				)
			)
		)
		(pad "2" smd custom
			(at 0 0.2794 270)
			(size 0.0762 0.0762)
			(layers "F.Cu" "F.Mask" "F.Paste")
			(net "PHY_SCC_B_TO_DRV_B_33_DN")
			(options
				(clearance outline)
				(anchor circle)
			)
			(primitives
				(gr_poly
					(pts
						(arc
							(start 0.1524 -0.127)
							(mid 0.137521 -0.162921)
							(end 0.1016 -0.1778)
						)
						(arc
							(start -0.1016 -0.1778)
							(mid -0.137521 -0.162921)
							(end -0.1524 -0.127)
						)
						(arc
							(start -0.1524 0.127)
							(mid -0.137521 0.162921)
							(end -0.1016 0.1778)
						)
						(arc
							(start 0.1016 0.1778)
							(mid 0.137521 0.162921)
							(end 0.1524 0.127)
						)
					)
					(width 0)
					(fill yes)
				)
			)
		)
	)
	(footprint ""
		(layer "F.Cu")
		(at 178.562 -11.4427 -90)
		(property "Reference" "R753"
			(at 0 0 270)
			(layer "F.SilkS")
			(hide yes)
			(effects
				(font
					(size 1.27 1.27)
				)
			)
		)
		(property "Value" "200KR2F-L-GP"
			(at 0.064008 -3.993896 270)
			(unlocked yes)
			(layer "F.Fab")
			(hide yes)
			(effects
				(font
					(size 1.016 1.016)
					(thickness 0.1524)
				)
			)
		)
		(property "Device Type" "R402H16"
			(at 0.064008 -5.517896 270)
			(unlocked yes)
			(layer "F.Fab")
			(hide yes)
			(effects
				(font
					(size 1.016 1.016)
					(thickness 0.1524)
				)
			)
		)
		(duplicate_pad_numbers_are_jumpers no)
		(fp_line
			(start -0.508 -0.9398)
			(end -0.508 0.9398)
			(stroke
				(width 0.1524)
				(type default)
			)
			(layer "F.SilkS")
		)
		(fp_line
			(start 0.508 -0.9398)
			(end -0.508 -0.9398)
			(stroke
				(width 0.1524)
				(type default)
			)
			(layer "F.SilkS")
		)
		(fp_rect
			(start -0.508 0.9398)
			(end 0.508 -0.9398)
			(stroke
				(width 0)
				(type default)
			)
			(fill no)
			(layer "F.CrtYd")
		)
		(fp_rect
			(start -0.508 0.9398)
			(end 0.508 -0.9398)
			(stroke
				(width 0)
				(type default)
			)
			(fill no)
			(layer "F.Fab")
		)
		(pad "1" smd custom
			(at 0 -0.4445 270)
			(size 0.1397 0.1397)
			(layers "F.Cu" "F.Mask" "F.Paste")
			(net "SW_HDD_R29")
			(options
				(clearance outline)
				(anchor circle)
			)
			(primitives
				(gr_poly
					(pts
						(arc
							(start -0.1778 -0.2794)
							(mid -0.249642 -0.249642)
							(end -0.2794 -0.1778)
						)
						(arc
							(start -0.2794 0.1778)
							(mid -0.249642 0.249642)
							(end -0.1778 0.2794)
						)
						(arc
							(start 0.1778 0.2794)
							(mid 0.249642 0.249642)
							(end 0.2794 0.1778)
						)
						(arc
							(start 0.2794 -0.1778)
							(mid 0.249642 -0.249642)
							(end 0.1778 -0.2794)
						)
					)
					(width 0)
					(fill yes)
				)
			)
		)
		(pad "2" smd custom
			(at 0 0.4445 270)
			(size 0.1397 0.1397)
			(layers "F.Cu" "F.Mask" "F.Paste")
			(net "SW_HDD_N29")
			(options
				(clearance outline)
				(anchor circle)
			)
			(primitives
				(gr_poly
					(pts
						(arc
							(start -0.1778 -0.2794)
							(mid -0.249642 -0.249642)
							(end -0.2794 -0.1778)
						)
						(arc
							(start -0.2794 0.1778)
							(mid -0.249642 0.249642)
							(end -0.1778 0.2794)
						)
						(arc
							(start 0.1778 0.2794)
							(mid 0.249642 0.249642)
							(end 0.2794 0.1778)
						)
						(arc
							(start 0.2794 -0.1778)
							(mid 0.249642 -0.249642)
							(end 0.1778 -0.2794)
						)
					)
					(width 0)
					(fill yes)
				)
			)
		)
	)
)
